# S9S_MB_2U (Grand Teton) — schematic netlist excerpt (pin names and nets, part order shuffled) for the footprints in the layout excerpt that follows; sources: Cadence DE-HDL packaged netlist, KiCad conversion of 03242023_DA0F0TMBIJ0_F0T_Motherboard_J_brd_V01_OCP.brd

PU289  MP5990GMA1111Z  MP5990GMA-1111-Z IC  pkg LGA45_TH_0-45_7X5  page 301
  VIN1  = P12V_PSU
  VIN2  = P12V_PSU
  VIN3  = P12V_PSU
  VIN4  = P12V_PSU
  VIN5  = P12V_PSU
  VIN6  = P12V_PSU
  VIN7  = P12V_PSU
  VIN8  = P12V_PSU
  VINSEN  = HSC_VSENSE
  \alt#\  = IRQ_SML1_PMBUS_ALERT
  SCL  = SMB_SML1_PMBUS_HSC_L_SCL
  SDA  = SMB_SML1_PMBUS_HSC_R_SDA
  \pg||ocw#\  = MB0_P12V_STBY_PWRGD
  \vin_uvw#\  = HSC_VIN_UVW_N
  VTEMP  = HSC_VTEMP
  SS  = HSC_SS
  VDD33_1  = HSC_VDD_R
  GND1  = AGND_HSC
  VDD18  = HSC_VDD18
  CS  = HSC_CS
  IMON  = HSC_IMON
  OCREF  = HSC_OCREF
  ADDR  = HSC_ADDR
  VOSEN  = HSC_VOSEN
  SCREF_OCWREF  = HSC_SCREF
  EN  = HSC_EN_R
  VOUT1  = P12V_AUX
  VOUT2  = P12V_AUX
  VOUT3  = P12V_AUX
  VOUT4  = P12V_AUX
  VOUT5  = P12V_AUX
  VOUT6  = P12V_AUX
  VOUT7  = P12V_AUX
  VOUT8  = P12V_AUX
  VOUT9  = P12V_AUX
  VOUT10  = P12V_AUX
  D_OC  = HSC_D_OC_R
  \on\  = HSC_ON_R
  GOK  = HSC_FAULT
  FLT_TYPE  = HSC_FLT_TYPE
  MODE  = HSC_MODE
  VIN9  = P12V_PSU
  VIN10  = P12V_PSU
  GND2  = AGND_HSC
  VDD33_2  = HSC_VDD_R

(kicad_pcb
	(version 20260206)
	(generator "pcbnew")
	(generator_version "10.0")
	(general
		(thickness 1.6)
		(legacy_teardrops no)
	)
	(paper "A4")
	(title_block
		(title "03242023_DA0F0TMBIJ0_F0T_Motherboard_J_brd_V01_OCP.brd")
		(comment 1 "Grand Teton / footprint 2009 of 6105 (PU289), pads 1-45 of 45")
	)
	(layers
		(0 "F.Cu" signal "TOP")
		(4 "In1.Cu" signal "GND")
		(6 "In2.Cu" signal "IN1")
		(8 "In3.Cu" signal "GND1")
		(10 "In4.Cu" signal "IN2")
		(12 "In5.Cu" signal "GND2")
		(14 "In6.Cu" signal "IN3")
		(16 "In7.Cu" signal "GND3")
		(18 "In8.Cu" signal "VCC")
		(20 "In9.Cu" signal "VCC1")
		(22 "In10.Cu" signal "GND4")
		(24 "In11.Cu" signal "IN4")
		(26 "In12.Cu" signal "GND5")
		(28 "In13.Cu" signal "IN5")
		(30 "In14.Cu" signal "GND6")
		(32 "In15.Cu" signal "IN6")
		(34 "In16.Cu" signal "GND7")
		(2 "B.Cu" signal "BOTTOM")
		(9 "F.Adhes" user "F.Adhesive")
		(11 "B.Adhes" user "B.Adhesive")
		(13 "F.Paste" user "Package Geometry/Pastemask Top")
		(15 "B.Paste" user "Package Geometry/Pastemask Bottom")
		(5 "F.SilkS" user "Ref Des/Silkscreen Top")
		(7 "B.SilkS" user "Ref Des/Silkscreen Bottom")
		(1 "F.Mask" user "Board Geometry/Soldermask Top")
		(3 "B.Mask" user "Board Geometry/Soldermask Bottom")
		(17 "Dwgs.User" user "User.Drawings")
		(19 "Cmts.User" user "User.Comments")
		(21 "Eco1.User" user "User.Eco1")
		(23 "Eco2.User" user "User.Eco2")
		(25 "Edge.Cuts" user "Board Geometry/Outline")
		(27 "Margin" user)
		(31 "F.CrtYd" user "Package Geometry/Place Bound Top")
		(29 "B.CrtYd" user "Package Geometry/Place Bound Bottom")
		(35 "F.Fab" user "Ref Des/Assembly Top")
		(33 "B.Fab" user "Ref Des/Assembly Bottom")
	)
	(footprint ""
		(layer "F.Cu")
		(at 185.91403 -402.722334 -90)
		(property "Reference" "PU289"
			(at -8.205978 -4.056126 0)
			(unlocked yes)
			(layer "F.SilkS")
			(effects
				(font
					(size 0.7874 0.5842)
					(thickness 0.1524)
				)
			)
		)
		(property "Value" ""
			(at 0 0 270)
			(layer "F.Fab")
			(effects
				(font
					(size 1.27 1.27)
				)
			)
		)
		(duplicate_pad_numbers_are_jumpers no)
		(pad "1" smd rect
			(at -2.237486 -2.70002)
			(size 0.2286 0.381)
			(layers "F.Cu" "F.Mask" "F.Paste")
			(net "P12V_PSU")
		)
		(pad "2" smd rect
			(at -2.237486 -2.249932)
			(size 0.2286 0.381)
			(layers "F.Cu" "F.Mask" "F.Paste")
			(net "P12V_PSU")
		)
		(pad "3" smd rect
			(at -2.237486 -1.800098)
			(size 0.2286 0.381)
			(layers "F.Cu" "F.Mask" "F.Paste")
			(net "P12V_PSU")
		)
		(pad "4" smd rect
			(at -2.237486 -1.35001)
			(size 0.2286 0.381)
			(layers "F.Cu" "F.Mask" "F.Paste")
			(net "P12V_PSU")
		)
		(pad "5" smd rect
			(at -2.237486 -0.899922)
			(size 0.2286 0.381)
			(layers "F.Cu" "F.Mask" "F.Paste")
			(net "P12V_PSU")
		)
		(pad "6" smd rect
			(at -2.237486 -0.450088)
			(size 0.2286 0.381)
			(layers "F.Cu" "F.Mask" "F.Paste")
			(net "P12V_PSU")
		)
		(pad "7" smd rect
			(at -2.237486 0)
			(size 0.2286 0.381)
			(layers "F.Cu" "F.Mask" "F.Paste")
			(net "P12V_PSU")
		)
		(pad "8" smd rect
			(at -2.237486 0.450088)
			(size 0.2286 0.381)
			(layers "F.Cu" "F.Mask" "F.Paste")
			(net "P12V_PSU")
		)
		(pad "9" smd rect
			(at -2.237486 0.899922)
			(size 0.2286 0.381)
			(layers "F.Cu" "F.Mask" "F.Paste")
			(net "HSC_VSENSE")
		)
		(pad "10" smd rect
			(at -2.237486 1.35001)
			(size 0.2286 0.381)
			(layers "F.Cu" "F.Mask" "F.Paste")
			(net "IRQ_SML1_PMBUS_ALERT")
		)
		(pad "11" smd rect
			(at -2.237486 1.800098)
			(size 0.2286 0.381)
			(layers "F.Cu" "F.Mask" "F.Paste")
			(net "SMB_SML1_PMBUS_HSC_L_SCL")
		)
		(pad "12" smd rect
			(at -2.237486 2.249932)
			(size 0.2286 0.381)
			(layers "F.Cu" "F.Mask" "F.Paste")
			(net "SMB_SML1_PMBUS_HSC_R_SDA")
		)
		(pad "13" smd rect
			(at -2.237486 2.70002)
			(size 0.2286 0.381)
			(layers "F.Cu" "F.Mask" "F.Paste")
			(net "MB0_P12V_STBY_PWRGD")
		)
		(pad "14" smd rect
			(at -1.575054 3.237484 270)
			(size 0.2286 0.381)
			(layers "F.Cu" "F.Mask" "F.Paste")
			(net "HSC_VIN_UVW_N")
		)
		(pad "15" smd rect
			(at -1.124966 3.237484 270)
			(size 0.2286 0.381)
			(layers "F.Cu" "F.Mask" "F.Paste")
			(net "HSC_VTEMP")
		)
		(pad "16" smd rect
			(at -0.674878 3.237484 270)
			(size 0.2286 0.381)
			(layers "F.Cu" "F.Mask" "F.Paste")
			(net "HSC_SS")
		)
		(pad "17" smd rect
			(at -0.225044 3.237484 270)
			(size 0.2286 0.381)
			(layers "F.Cu" "F.Mask" "F.Paste")
			(net "HSC_VDD_R")
		)
		(pad "18" smd rect
			(at 0.225044 3.237484 270)
			(size 0.2286 0.381)
			(layers "F.Cu" "F.Mask" "F.Paste")
			(net "AGND_HSC")
		)
		(pad "19" smd rect
			(at 0.674878 3.237484 270)
			(size 0.2286 0.381)
			(layers "F.Cu" "F.Mask" "F.Paste")
			(net "HSC_VDD18")
		)
		(pad "20" smd rect
			(at 1.124966 3.237484 270)
			(size 0.2286 0.381)
			(layers "F.Cu" "F.Mask" "F.Paste")
			(net "HSC_CS")
		)
		(pad "21" smd rect
			(at 1.575054 3.237484 270)
			(size 0.2286 0.381)
			(layers "F.Cu" "F.Mask" "F.Paste")
			(net "HSC_IMON")
		)
		(pad "22" smd rect
			(at 2.237486 2.70002)
			(size 0.2286 0.381)
			(layers "F.Cu" "F.Mask" "F.Paste")
			(net "HSC_OCREF")
		)
		(pad "23" smd rect
			(at 2.237486 2.249932)
			(size 0.2286 0.381)
			(layers "F.Cu" "F.Mask" "F.Paste")
			(net "HSC_ADDR")
		)
		(pad "24" smd rect
			(at 2.237486 1.800098)
			(size 0.2286 0.381)
			(layers "F.Cu" "F.Mask" "F.Paste")
			(net "HSC_VOSEN")
		)
		(pad "25" smd rect
			(at 2.237486 1.35001)
			(size 0.2286 0.381)
			(layers "F.Cu" "F.Mask" "F.Paste")
			(net "HSC_SCREF")
		)
		(pad "26" smd rect
			(at 2.237486 0.899922)
			(size 0.2286 0.381)
			(layers "F.Cu" "F.Mask" "F.Paste")
			(net "HSC_EN_R")
		)
		(pad "27" smd rect
			(at 2.237486 0.450088)
			(size 0.2286 0.381)
			(layers "F.Cu" "F.Mask" "F.Paste")
			(net "P12V_AUX")
		)
		(pad "28" smd rect
			(at 2.237486 0)
			(size 0.2286 0.381)
			(layers "F.Cu" "F.Mask" "F.Paste")
			(net "P12V_AUX")
		)
		(pad "29" smd rect
			(at 2.237486 -0.450088)
			(size 0.2286 0.381)
			(layers "F.Cu" "F.Mask" "F.Paste")
			(net "P12V_AUX")
		)
		(pad "30" smd rect
			(at 2.237486 -0.899922)
			(size 0.2286 0.381)
			(layers "F.Cu" "F.Mask" "F.Paste")
			(net "P12V_AUX")
		)
		(pad "31" smd rect
			(at 2.237486 -1.35001)
			(size 0.2286 0.381)
			(layers "F.Cu" "F.Mask" "F.Paste")
			(net "P12V_AUX")
		)
		(pad "32" smd rect
			(at 2.237486 -1.800098)
			(size 0.2286 0.381)
			(layers "F.Cu" "F.Mask" "F.Paste")
			(net "P12V_AUX")
		)
		(pad "33" smd rect
			(at 2.237486 -2.249932)
			(size 0.2286 0.381)
			(layers "F.Cu" "F.Mask" "F.Paste")
			(net "P12V_AUX")
		)
		(pad "34" smd rect
			(at 2.237486 -2.70002)
			(size 0.2286 0.381)
			(layers "F.Cu" "F.Mask" "F.Paste")
			(net "P12V_AUX")
		)
		(pad "35" smd rect
			(at 1.575054 -3.237484 270)
			(size 0.2286 0.381)
			(layers "F.Cu" "F.Mask" "F.Paste")
			(net "P12V_AUX")
		)
		(pad "36" smd rect
			(at 1.124966 -3.237484 270)
			(size 0.2286 0.381)
			(layers "F.Cu" "F.Mask" "F.Paste")
			(net "P12V_AUX")
		)
		(pad "37" smd rect
			(at 0.674878 -3.237484 270)
			(size 0.2286 0.381)
			(layers "F.Cu" "F.Mask" "F.Paste")
			(net "HSC_D_OC_R")
		)
		(pad "38" smd rect
			(at 0.225044 -3.237484 270)
			(size 0.2286 0.381)
			(layers "F.Cu" "F.Mask" "F.Paste")
			(net "HSC_ON_R")
		)
		(pad "39" smd rect
			(at -0.225044 -3.237484 270)
			(size 0.2286 0.381)
			(layers "F.Cu" "F.Mask" "F.Paste")
			(net "HSC_FAULT")
		)
		(pad "40" smd rect
			(at -0.674878 -3.237484 270)
			(size 0.2286 0.381)
			(layers "F.Cu" "F.Mask" "F.Paste")
			(net "HSC_FLT_TYPE")
		)
		(pad "41" smd rect
			(at -1.124966 -3.237484 270)
			(size 0.2286 0.381)
			(layers "F.Cu" "F.Mask" "F.Paste")
			(net "HSC_MODE")
		)
		(pad "42" smd rect
			(at -1.575054 -3.237484 270)
			(size 0.2286 0.381)
			(layers "F.Cu" "F.Mask" "F.Paste")
			(net "P12V_PSU")
		)
		(pad "43" smd rect
			(at 0 -0.999998 270)
			(size 3.4036 3.4036)
			(layers "F.Cu" "F.Mask" "F.Paste")
			(net "P12V_PSU")
		)
		(pad "44" smd rect
			(at -1.124966 1.89992 270)
			(size 1.1684 1.6002)
			(layers "F.Cu" "F.Mask" "F.Paste")
			(net "AGND_HSC")
		)
		(pad "45" smd rect
			(at 1.124966 1.89992 270)
			(size 1.1684 1.6002)
			(layers "F.Cu" "F.Mask" "F.Paste")
			(net "HSC_VDD_R")
		)
	)
)
